(kicad_pcb
	(version 20260206)
	(generator "pcbnew")
	(generator_version "10.0")
	(general
		(thickness 1.6)
		(legacy_teardrops no)
	)
	(paper "A4")
	(title_block
		(title "03242023_DA0F0TMBIJ0_F0T_Motherboard_J_brd_V01_OCP.brd")
		(comment 1 "Grand Teton / footprints 4310-4316 of 6105")
	)
	(layers
		(0 "F.Cu" signal "TOP")
		(4 "In1.Cu" signal "GND")
		(6 "In2.Cu" signal "IN1")
		(8 "In3.Cu" signal "GND1")
		(10 "In4.Cu" signal "IN2")
		(12 "In5.Cu" signal "GND2")
		(14 "In6.Cu" signal "IN3")
		(16 "In7.Cu" signal "GND3")
		(18 "In8.Cu" signal "VCC")
		(20 "In9.Cu" signal "VCC1")
		(22 "In10.Cu" signal "GND4")
		(24 "In11.Cu" signal "IN4")
		(26 "In12.Cu" signal "GND5")
		(28 "In13.Cu" signal "IN5")
		(30 "In14.Cu" signal "GND6")
		(32 "In15.Cu" signal "IN6")
		(34 "In16.Cu" signal "GND7")
		(2 "B.Cu" signal "BOTTOM")
		(9 "F.Adhes" user "F.Adhesive")
		(11 "B.Adhes" user "B.Adhesive")
		(13 "F.Paste" user "Package Geometry/Pastemask Top")
		(15 "B.Paste" user "Package Geometry/Pastemask Bottom")
		(5 "F.SilkS" user "Ref Des/Silkscreen Top")
		(7 "B.SilkS" user "Ref Des/Silkscreen Bottom")
		(1 "F.Mask" user "Board Geometry/Soldermask Top")
		(3 "B.Mask" user "Board Geometry/Soldermask Bottom")
		(17 "Dwgs.User" user "User.Drawings")
		(19 "Cmts.User" user "User.Comments")
		(21 "Eco1.User" user "User.Eco1")
		(23 "Eco2.User" user "User.Eco2")
		(25 "Edge.Cuts" user "Board Geometry/Outline")
		(27 "Margin" user)
		(31 "F.CrtYd" user "Package Geometry/Place Bound Top")
		(29 "B.CrtYd" user "Package Geometry/Place Bound Bottom")
		(35 "F.Fab" user "Ref Des/Assembly Top")
		(33 "B.Fab" user "Ref Des/Assembly Bottom")
	)
	(footprint ""
		(layer "B.Cu")
		(at 76.463652 -183.470296 -90)
		(property "Reference" "R62"
			(at 0 0 90)
			(layer "B.SilkS")
			(hide yes)
			(effects
				(font
					(size 1.27 1.27)
				)
				(justify mirror)
			)
		)
		(property "Value" ""
			(at 0 0 90)
			(layer "B.Fab")
			(effects
				(font
					(size 1.27 1.27)
				)
				(justify mirror)
			)
		)
		(duplicate_pad_numbers_are_jumpers no)
		(fp_line
			(start -0.7874 0.4064)
			(end 0.7874 0.4064)
			(stroke
				(width 0.1524)
				(type default)
			)
			(layer "B.SilkS")
		)
		(fp_line
			(start 0.7874 0.4064)
			(end 0.7874 -0.4064)
			(stroke
				(width 0.1524)
				(type default)
			)
			(layer "B.SilkS")
		)
		(fp_line
			(start -0.7874 -0.4064)
			(end -0.7874 0.4064)
			(stroke
				(width 0.1524)
				(type default)
			)
			(layer "B.SilkS")
		)
		(fp_line
			(start 0.7874 -0.4064)
			(end -0.7874 -0.4064)
			(stroke
				(width 0.1524)
				(type default)
			)
			(layer "B.SilkS")
		)
		(fp_line
			(start -0.67945 0.3048)
			(end -0.120396 0.3048)
			(stroke
				(width 0.1)
				(type default)
			)
			(layer "B.Fab")
		)
		(fp_line
			(start -0.120396 0.3048)
			(end -0.120396 0.2794)
			(stroke
				(width 0.1)
				(type default)
			)
			(layer "B.Fab")
		)
		(fp_line
			(start 0.12065 0.3048)
			(end 0.67945 0.3048)
			(stroke
				(width 0.1)
				(type default)
			)
			(layer "B.Fab")
		)
		(fp_line
			(start 0.67945 0.3048)
			(end 0.67945 -0.305054)
			(stroke
				(width 0.1)
				(type default)
			)
			(layer "B.Fab")
		)
		(fp_line
			(start -0.120396 0.2794)
			(end 0.12065 0.2794)
			(stroke
				(width 0.1)
				(type default)
			)
			(layer "B.Fab")
		)
		(fp_line
			(start 0.12065 0.2794)
			(end 0.12065 0.3048)
			(stroke
				(width 0.1)
				(type default)
			)
			(layer "B.Fab")
		)
		(fp_line
			(start -0.12065 -0.2794)
			(end -0.12065 -0.3048)
			(stroke
				(width 0.1)
				(type default)
			)
			(layer "B.Fab")
		)
		(fp_line
			(start 0.12065 -0.2794)
			(end -0.12065 -0.2794)
			(stroke
				(width 0.1)
				(type default)
			)
			(layer "B.Fab")
		)
		(fp_line
			(start -0.67945 -0.3048)
			(end -0.67945 0.3048)
			(stroke
				(width 0.1)
				(type default)
			)
			(layer "B.Fab")
		)
		(fp_line
			(start -0.12065 -0.3048)
			(end -0.67945 -0.3048)
			(stroke
				(width 0.1)
				(type default)
			)
			(layer "B.Fab")
		)
		(fp_line
			(start 0.12065 -0.305054)
			(end 0.12065 -0.2794)
			(stroke
				(width 0.1)
				(type default)
			)
			(layer "B.Fab")
		)
		(fp_line
			(start 0.67945 -0.305054)
			(end 0.12065 -0.305054)
			(stroke
				(width 0.1)
				(type default)
			)
			(layer "B.Fab")
		)
		(pad "1" smd circle
			(at 0.40005 0 90)
			(size 0 0)
			(layers "B.Cu" "B.Mask" "B.Paste")
			(net "H_CPU_PREQ_QS_GTL_N")
		)
		(pad "2" smd circle
			(at -0.40005 0 90)
			(size 0 0)
			(layers "B.Cu" "B.Mask" "B.Paste")
			(net "H_CPU1_PREQ_QS_GTL_R_N")
		)
	)
	(footprint ""
		(layer "B.Cu")
		(at 173.913546 -321.554856 -90)
		(property "Reference" "C86"
			(at 0 0 90)
			(layer "B.SilkS")
			(hide yes)
			(effects
				(font
					(size 1.27 1.27)
				)
				(justify mirror)
			)
		)
		(property "Value" ""
			(at 0 0 90)
			(layer "B.Fab")
			(effects
				(font
					(size 1.27 1.27)
				)
				(justify mirror)
			)
		)
		(duplicate_pad_numbers_are_jumpers no)
		(fp_line
			(start -1.524 0.762)
			(end 1.524 0.762)
			(stroke
				(width 0.1524)
				(type default)
			)
			(layer "B.SilkS")
		)
		(fp_line
			(start 1.524 0.762)
			(end 1.524 -0.762)
			(stroke
				(width 0.1524)
				(type default)
			)
			(layer "B.SilkS")
		)
		(fp_line
			(start -1.524 -0.762)
			(end -1.524 0.762)
			(stroke
				(width 0.1524)
				(type default)
			)
			(layer "B.SilkS")
		)
		(fp_line
			(start 1.524 -0.762)
			(end -1.524 -0.762)
			(stroke
				(width 0.1524)
				(type default)
			)
			(layer "B.SilkS")
		)
		(fp_line
			(start -1.1049 0.724916)
			(end -1.1049 -0.724916)
			(stroke
				(width 0.1)
				(type default)
			)
			(layer "B.Fab")
		)
		(fp_line
			(start 1.1049 0.724916)
			(end -1.1049 0.724916)
			(stroke
				(width 0.1)
				(type default)
			)
			(layer "B.Fab")
		)
		(fp_line
			(start -1.1049 -0.724916)
			(end 1.1049 -0.724916)
			(stroke
				(width 0.1)
				(type default)
			)
			(layer "B.Fab")
		)
		(fp_line
			(start 1.1049 -0.724916)
			(end 1.1049 0.724916)
			(stroke
				(width 0.1)
				(type default)
			)
			(layer "B.Fab")
		)
		(pad "1" smd rect
			(at 0.889 0 270)
			(size 1.016 1.27)
			(layers "B.Cu" "B.Mask" "B.Paste")
			(net "P12V_S3_AUX_CPU1_NVDIMM")
		)
		(pad "2" smd rect
			(at -0.889 0 270)
			(size 1.016 1.27)
			(layers "B.Cu" "B.Mask" "B.Paste")
			(net "GND")
		)
	)
	(footprint ""
		(layer "B.Cu")
		(at 423.338244 -193.353436 -90)
		(property "Reference" "R842"
			(at 0 0 90)
			(layer "B.SilkS")
			(hide yes)
			(effects
				(font
					(size 1.27 1.27)
				)
				(justify mirror)
			)
		)
		(property "Value" ""
			(at 0 0 90)
			(layer "B.Fab")
			(effects
				(font
					(size 1.27 1.27)
				)
				(justify mirror)
			)
		)
		(duplicate_pad_numbers_are_jumpers no)
		(fp_line
			(start -0.7874 0.4064)
			(end 0.7874 0.4064)
			(stroke
				(width 0.1524)
				(type default)
			)
			(layer "B.SilkS")
		)
		(fp_line
			(start 0.7874 0.4064)
			(end 0.7874 -0.4064)
			(stroke
				(width 0.1524)
				(type default)
			)
			(layer "B.SilkS")
		)
		(fp_line
			(start -0.7874 -0.4064)
			(end -0.7874 0.4064)
			(stroke
				(width 0.1524)
				(type default)
			)
			(layer "B.SilkS")
		)
		(fp_line
			(start 0.7874 -0.4064)
			(end -0.7874 -0.4064)
			(stroke
				(width 0.1524)
				(type default)
			)
			(layer "B.SilkS")
		)
		(fp_line
			(start -0.67945 0.3048)
			(end -0.120396 0.3048)
			(stroke
				(width 0.1)
				(type default)
			)
			(layer "B.Fab")
		)
		(fp_line
			(start -0.120396 0.3048)
			(end -0.120396 0.2794)
			(stroke
				(width 0.1)
				(type default)
			)
			(layer "B.Fab")
		)
		(fp_line
			(start 0.12065 0.3048)
			(end 0.67945 0.3048)
			(stroke
				(width 0.1)
				(type default)
			)
			(layer "B.Fab")
		)
		(fp_line
			(start 0.67945 0.3048)
			(end 0.67945 -0.305054)
			(stroke
				(width 0.1)
				(type default)
			)
			(layer "B.Fab")
		)
		(fp_line
			(start -0.120396 0.2794)
			(end 0.12065 0.2794)
			(stroke
				(width 0.1)
				(type default)
			)
			(layer "B.Fab")
		)
		(fp_line
			(start 0.12065 0.2794)
			(end 0.12065 0.3048)
			(stroke
				(width 0.1)
				(type default)
			)
			(layer "B.Fab")
		)
		(fp_line
			(start -0.12065 -0.2794)
			(end -0.12065 -0.3048)
			(stroke
				(width 0.1)
				(type default)
			)
			(layer "B.Fab")
		)
		(fp_line
			(start 0.12065 -0.2794)
			(end -0.12065 -0.2794)
			(stroke
				(width 0.1)
				(type default)
			)
			(layer "B.Fab")
		)
		(fp_line
			(start -0.67945 -0.3048)
			(end -0.67945 0.3048)
			(stroke
				(width 0.1)
				(type default)
			)
			(layer "B.Fab")
		)
		(fp_line
			(start -0.12065 -0.3048)
			(end -0.67945 -0.3048)
			(stroke
				(width 0.1)
				(type default)
			)
			(layer "B.Fab")
		)
		(fp_line
			(start 0.12065 -0.305054)
			(end 0.12065 -0.2794)
			(stroke
				(width 0.1)
				(type default)
			)
			(layer "B.Fab")
		)
		(fp_line
			(start 0.67945 -0.305054)
			(end 0.12065 -0.305054)
			(stroke
				(width 0.1)
				(type default)
			)
			(layer "B.Fab")
		)
		(pad "1" smd circle
			(at 0.40005 0 90)
			(size 0 0)
			(layers "B.Cu" "B.Mask" "B.Paste")
			(net "PVCCD_HV_CPU0")
		)
		(pad "2" smd circle
			(at -0.40005 0 90)
			(size 0 0)
			(layers "B.Cu" "B.Mask" "B.Paste")
			(net "RST_M_EF_CPU0_FPGA_N")
		)
	)
	(footprint ""
		(layer "B.Cu")
		(at 264.541 -98.008948 90)
		(property "Reference" "L1"
			(at 0 0 90)
			(layer "B.SilkS")
			(hide yes)
			(effects
				(font
					(size 1.27 1.27)
				)
				(justify mirror)
			)
		)
		(property "Value" ""
			(at 0 0 90)
			(layer "B.Fab")
			(effects
				(font
					(size 1.27 1.27)
				)
				(justify mirror)
			)
		)
		(duplicate_pad_numbers_are_jumpers no)
		(fp_line
			(start 1.63576 -0.8128)
			(end -1.63576 -0.8128)
			(stroke
				(width 0.1524)
				(type default)
			)
			(layer "B.SilkS")
		)
		(fp_line
			(start 1.63576 -0.8128)
			(end 1.63576 0.8128)
			(stroke
				(width 0.1524)
				(type default)
			)
			(layer "B.SilkS")
		)
		(fp_line
			(start -1.63576 -0.8128)
			(end -1.63576 0.8128)
			(stroke
				(width 0.1524)
				(type default)
			)
			(layer "B.SilkS")
		)
		(fp_line
			(start -1.63576 0.8128)
			(end 1.63576 0.8128)
			(stroke
				(width 0.1524)
				(type default)
			)
			(layer "B.SilkS")
		)
		(fp_line
			(start 1.56083 -0.738632)
			(end 1.56083 0.7366)
			(stroke
				(width 0.1)
				(type default)
			)
			(layer "B.Fab")
		)
		(fp_line
			(start -1.560576 -0.738632)
			(end 1.56083 -0.738632)
			(stroke
				(width 0.1)
				(type default)
			)
			(layer "B.Fab")
		)
		(fp_line
			(start 1.56083 0.7366)
			(end 1.524 0.7366)
			(stroke
				(width 0.1)
				(type default)
			)
			(layer "B.Fab")
		)
		(fp_line
			(start 1.524 0.7366)
			(end -1.524 0.7366)
			(stroke
				(width 0.1)
				(type default)
			)
			(layer "B.Fab")
		)
		(fp_line
			(start -1.524 0.7366)
			(end -1.560576 0.7366)
			(stroke
				(width 0.1)
				(type default)
			)
			(layer "B.Fab")
		)
		(fp_line
			(start -1.560576 0.7366)
			(end -1.560576 -0.738632)
			(stroke
				(width 0.1)
				(type default)
			)
			(layer "B.Fab")
		)
		(pad "1" smd rect
			(at 0.94996 0 90)
			(size 1.1176 1.3716)
			(layers "B.Cu" "B.Mask" "B.Paste")
			(net "P3V3_AUX")
		)
		(pad "2" smd rect
			(at -0.94996 0 90)
			(size 1.1176 1.3716)
			(layers "B.Cu" "B.Mask" "B.Paste")
			(net "P3V3_AUX_CLK_GEN_VDD_CK440")
		)
	)
	(footprint ""
		(layer "B.Cu")
		(at 178.10988 -101.564948 180)
		(property "Reference" "R3345"
			(at 0 0 0)
			(layer "B.SilkS")
			(hide yes)
			(effects
				(font
					(size 1.27 1.27)
				)
				(justify mirror)
			)
		)
		(property "Value" ""
			(at 0 0 0)
			(layer "B.Fab")
			(effects
				(font
					(size 1.27 1.27)
				)
				(justify mirror)
			)
		)
		(duplicate_pad_numbers_are_jumpers no)
		(fp_line
			(start 1.2954 0.5842)
			(end 1.2954 -0.5842)
			(stroke
				(width 0.1524)
				(type default)
			)
			(layer "B.SilkS")
		)
		(fp_line
			(start 1.2954 -0.5842)
			(end -1.2954 -0.5842)
			(stroke
				(width 0.1524)
				(type default)
			)
			(layer "B.SilkS")
		)
		(fp_line
			(start -1.2954 0.5842)
			(end 1.2954 0.5842)
			(stroke
				(width 0.1524)
				(type default)
			)
			(layer "B.SilkS")
		)
		(fp_line
			(start -1.2954 -0.5842)
			(end -1.2954 0.5842)
			(stroke
				(width 0.1524)
				(type default)
			)
			(layer "B.SilkS")
		)
		(fp_line
			(start 1.1938 0.4064)
			(end 1.1938 -0.406654)
			(stroke
				(width 0.1)
				(type default)
			)
			(layer "B.Fab")
		)
		(fp_line
			(start 1.1938 -0.406654)
			(end 0.8636 -0.406654)
			(stroke
				(width 0.1)
				(type default)
			)
			(layer "B.Fab")
		)
		(fp_line
			(start 0.8636 0.4572)
			(end 0.8636 0.4318)
			(stroke
				(width 0.1)
				(type default)
			)
			(layer "B.Fab")
		)
		(fp_line
			(start 0.8636 0.4318)
			(end 0.8636 0.4064)
			(stroke
				(width 0.1)
				(type default)
			)
			(layer "B.Fab")
		)
		(fp_line
			(start 0.8636 0.4064)
			(end 1.1938 0.4064)
			(stroke
				(width 0.1)
				(type default)
			)
			(layer "B.Fab")
		)
		(fp_line
			(start 0.8636 -0.406654)
			(end 0.8636 -0.4572)
			(stroke
				(width 0.1)
				(type default)
			)
			(layer "B.Fab")
		)
		(fp_line
			(start 0.8636 -0.4572)
			(end -0.8636 -0.4572)
			(stroke
				(width 0.1)
				(type default)
			)
			(layer "B.Fab")
		)
		(fp_line
			(start -0.8636 0.4572)
			(end 0.8636 0.4572)
			(stroke
				(width 0.1)
				(type default)
			)
			(layer "B.Fab")
		)
		(fp_line
			(start -0.8636 0.4064)
			(end -0.8636 0.4572)
			(stroke
				(width 0.1)
				(type default)
			)
			(layer "B.Fab")
		)
		(fp_line
			(start -0.8636 -0.406654)
			(end -1.1938 -0.406654)
			(stroke
				(width 0.1)
				(type default)
			)
			(layer "B.Fab")
		)
		(fp_line
			(start -0.8636 -0.4572)
			(end -0.8636 -0.406654)
			(stroke
				(width 0.1)
				(type default)
			)
			(layer "B.Fab")
		)
		(fp_line
			(start -1.1938 0.4064)
			(end -0.8636 0.4064)
			(stroke
				(width 0.1)
				(type default)
			)
			(layer "B.Fab")
		)
		(fp_line
			(start -1.1938 -0.406654)
			(end -1.1938 0.4064)
			(stroke
				(width 0.1)
				(type default)
			)
			(layer "B.Fab")
		)
		(pad "1" smd rect
			(at 0.7366 0 90)
			(size 0.7112 0.8128)
			(layers "B.Cu" "B.Mask" "B.Paste")
			(net "P3V3_AUX")
		)
		(pad "2" smd rect
			(at -0.7366 0 90)
			(size 0.7112 0.8128)
			(layers "B.Cu" "B.Mask" "B.Paste")
			(net "P3V3_AUX_FPGA_VCCIO4")
		)
	)
	(footprint ""
		(layer "B.Cu")
		(at 176.45888 -123.948698 -90)
		(property "Reference" "C1946"
			(at 0 0 90)
			(layer "B.SilkS")
			(hide yes)
			(effects
				(font
					(size 1.27 1.27)
				)
				(justify mirror)
			)
		)
		(property "Value" ""
			(at 0 0 90)
			(layer "B.Fab")
			(effects
				(font
					(size 1.27 1.27)
				)
				(justify mirror)
			)
		)
		(duplicate_pad_numbers_are_jumpers no)
		(fp_line
			(start -0.7874 0.4064)
			(end 0.7874 0.4064)
			(stroke
				(width 0.1524)
				(type default)
			)
			(layer "B.SilkS")
		)
		(fp_line
			(start 0.7874 0.4064)
			(end 0.7874 -0.4064)
			(stroke
				(width 0.1524)
				(type default)
			)
			(layer "B.SilkS")
		)
		(fp_line
			(start -0.7874 -0.4064)
			(end -0.7874 0.4064)
			(stroke
				(width 0.1524)
				(type default)
			)
			(layer "B.SilkS")
		)
		(fp_line
			(start 0.7874 -0.4064)
			(end -0.7874 -0.4064)
			(stroke
				(width 0.1524)
				(type default)
			)
			(layer "B.SilkS")
		)
		(fp_line
			(start -0.67945 0.3048)
			(end -0.120396 0.3048)
			(stroke
				(width 0.1)
				(type default)
			)
			(layer "B.Fab")
		)
		(fp_line
			(start -0.120396 0.3048)
			(end -0.120396 0.2794)
			(stroke
				(width 0.1)
				(type default)
			)
			(layer "B.Fab")
		)
		(fp_line
			(start 0.12065 0.3048)
			(end 0.67945 0.3048)
			(stroke
				(width 0.1)
				(type default)
			)
			(layer "B.Fab")
		)
		(fp_line
			(start 0.67945 0.3048)
			(end 0.67945 -0.305054)
			(stroke
				(width 0.1)
				(type default)
			)
			(layer "B.Fab")
		)
		(fp_line
			(start -0.120396 0.2794)
			(end 0.12065 0.2794)
			(stroke
				(width 0.1)
				(type default)
			)
			(layer "B.Fab")
		)
		(fp_line
			(start 0.12065 0.2794)
			(end 0.12065 0.3048)
			(stroke
				(width 0.1)
				(type default)
			)
			(layer "B.Fab")
		)
		(fp_line
			(start -0.12065 -0.2794)
			(end -0.12065 -0.3048)
			(stroke
				(width 0.1)
				(type default)
			)
			(layer "B.Fab")
		)
		(fp_line
			(start 0.12065 -0.2794)
			(end -0.12065 -0.2794)
			(stroke
				(width 0.1)
				(type default)
			)
			(layer "B.Fab")
		)
		(fp_line
			(start -0.67945 -0.3048)
			(end -0.67945 0.3048)
			(stroke
				(width 0.1)
				(type default)
			)
			(layer "B.Fab")
		)
		(fp_line
			(start -0.12065 -0.3048)
			(end -0.67945 -0.3048)
			(stroke
				(width 0.1)
				(type default)
			)
			(layer "B.Fab")
		)
		(fp_line
			(start 0.12065 -0.305054)
			(end 0.12065 -0.2794)
			(stroke
				(width 0.1)
				(type default)
			)
			(layer "B.Fab")
		)
		(fp_line
			(start 0.67945 -0.305054)
			(end 0.12065 -0.305054)
			(stroke
				(width 0.1)
				(type default)
			)
			(layer "B.Fab")
		)
		(pad "1" smd circle
			(at 0.40005 0 90)
			(size 0 0)
			(layers "B.Cu" "B.Mask" "B.Paste")
			(net "P3V3_AUX_FPGA_VCCIO1")
		)
		(pad "2" smd circle
			(at -0.40005 0 90)
			(size 0 0)
			(layers "B.Cu" "B.Mask" "B.Paste")
			(net "GND")
		)
	)
	(footprint ""
		(layer "B.Cu")
		(at 385.46405 -190.82131 90)
		(property "Reference" "R69"
			(at 0 0 90)
			(layer "B.SilkS")
			(hide yes)
			(effects
				(font
					(size 1.27 1.27)
				)
				(justify mirror)
			)
		)
		(property "Value" ""
			(at 0 0 90)
			(layer "B.Fab")
			(effects
				(font
					(size 1.27 1.27)
				)
				(justify mirror)
			)
		)
		(duplicate_pad_numbers_are_jumpers no)
		(fp_line
			(start 0.7874 -0.4064)
			(end -0.7874 -0.4064)
			(stroke
				(width 0.1524)
				(type default)
			)
			(layer "B.SilkS")
		)
		(fp_line
			(start -0.7874 -0.4064)
			(end -0.7874 0.4064)
			(stroke
				(width 0.1524)
				(type default)
			)
			(layer "B.SilkS")
		)
		(fp_line
			(start 0.7874 0.4064)
			(end 0.7874 -0.4064)
			(stroke
				(width 0.1524)
				(type default)
			)
			(layer "B.SilkS")
		)
		(fp_line
			(start -0.7874 0.4064)
			(end 0.7874 0.4064)
			(stroke
				(width 0.1524)
				(type default)
			)
			(layer "B.SilkS")
		)
		(fp_line
			(start 0.67945 -0.305054)
			(end 0.12065 -0.305054)
			(stroke
				(width 0.1)
				(type default)
			)
			(layer "B.Fab")
		)
		(fp_line
			(start 0.12065 -0.305054)
			(end 0.12065 -0.2794)
			(stroke
				(width 0.1)
				(type default)
			)
			(layer "B.Fab")
		)
		(fp_line
			(start -0.12065 -0.3048)
			(end -0.67945 -0.3048)
			(stroke
				(width 0.1)
				(type default)
			)
			(layer "B.Fab")
		)
		(fp_line
			(start -0.67945 -0.3048)
			(end -0.67945 0.3048)
			(stroke
				(width 0.1)
				(type default)
			)
			(layer "B.Fab")
		)
		(fp_line
			(start 0.12065 -0.2794)
			(end -0.12065 -0.2794)
			(stroke
				(width 0.1)
				(type default)
			)
			(layer "B.Fab")
		)
		(fp_line
			(start -0.12065 -0.2794)
			(end -0.12065 -0.3048)
			(stroke
				(width 0.1)
				(type default)
			)
			(layer "B.Fab")
		)
		(fp_line
			(start 0.12065 0.2794)
			(end 0.12065 0.3048)
			(stroke
				(width 0.1)
				(type default)
			)
			(layer "B.Fab")
		)
		(fp_line
			(start -0.120396 0.2794)
			(end 0.12065 0.2794)
			(stroke
				(width 0.1)
				(type default)
			)
			(layer "B.Fab")
		)
		(fp_line
			(start 0.67945 0.3048)
			(end 0.67945 -0.305054)
			(stroke
				(width 0.1)
				(type default)
			)
			(layer "B.Fab")
		)
		(fp_line
			(start 0.12065 0.3048)
			(end 0.67945 0.3048)
			(stroke
				(width 0.1)
				(type default)
			)
			(layer "B.Fab")
		)
		(fp_line
			(start -0.120396 0.3048)
			(end -0.120396 0.2794)
			(stroke
				(width 0.1)
				(type default)
			)
			(layer "B.Fab")
		)
		(fp_line
			(start -0.67945 0.3048)
			(end -0.120396 0.3048)
			(stroke
				(width 0.1)
				(type default)
			)
			(layer "B.Fab")
		)
		(pad "1" smd circle
			(at 0.40005 0 270)
			(size 0 0)
			(layers "B.Cu" "B.Mask" "B.Paste")
			(net "PWRGD_PLT_AUX_CPU0_LVT3")
		)
		(pad "2" smd circle
			(at -0.40005 0 270)
			(size 0 0)
			(layers "B.Cu" "B.Mask" "B.Paste")
			(net "GND")
		)
	)
)
